# Lightning_PEB_EQL.xlsx — DDR3 (si-constraints)
| DATA | Signal name | Length | Differential mismatching < 10mil | MAX length < 2000mil |
|  | DDR3 DQS/DQS |  |  |  |
|  | MemDQS_P1 | 1045.02 | OK | OK |
|  | MemDQS_N1 | 1043.93 |  |  |
|  | MemDQS_P0 | 1039.6300000000001 | OK |  |
|  | MemDQS_N0 | 1041.8900000000001 |  |  |
|  | Signal name | Length | group mismatching<40 mil |  |
|  | DDR3 DQL |  |  |  |
|  | MemDQ_0 | 1044.01 | OK |  |
|  | MemDQ_1 | 1033.76 |  |  |
|  | MemDQ_2 | 1046.82 |  |  |
|  | MemDQ_3 | 1057.52 |  |  |
|  | MemDQ_4 | 1050.33 |  |  |
|  | MemDQ_5 | 1042.78 |  |  |
|  | MemDQ_6 | 1063.01 |  |  |
|  | MemDQ_7 | 1040.18 |  |  |
|  | Signal name | Length | group mismatching < 40 mil |  |
|  | DDR3 DQU |  |  |  |
|  | MemDQ_8 | 1046.6400000000001 | OK |  |
|  | MemDQ_9 | 1043.56 |  |  |
|  | MemDQ_10 | 1036.32 |  |  |
|  | MemDQ_11 | 1050.72 |  |  |
|  | MemDQ_12 | 1029.73 |  |  |
|  | MemDQ_13 | 1055.5999999999999 |  |  |
|  | MemDQ_14 | 1051.1600000000001 |  |  |
|  | MemDQ_15 | 1064.3900000000001 |  |  |
|  | Signal name | Length | group mismatching  <40 mil |  |
|  | DDR3 CLK |  |  |  |
|  | MemDM_1 | 1065.32 | OK |  |
|  | MemDM_0 | 1038.9000000000001 |  |  |
| CLK | Signal name | Length | Differential mismatching  <10 mil |  |
|  | DDR3 CLK |  |  |  |
|  | MemCK_P | 1074.9100000000001 | OK |  |
|  | MemCK_N | 1076.0899999999999 |  |  |
| COMMAND / ADDRESS | Signal name | Length | group mismatching < 100 mil |  |
|  | DDR3 DQU |  |  |  |
|  | MemA_0 | 1043.55 | OK |  |
|  | MemA_1 | 1039.1500000000001 |  |  |
|  | MemA_2 | 1054.58 |  |  |
|  | MemA_3 | 1033.53 |  |  |
|  | MemA_4 | 1052.67 |  |  |
|  | MemA_5 | 1048.1600000000001 |  |  |
|  | MemA_6 | 1040.46 |  |  |
|  | MemA_7 | 1059.9100000000001 |  |  |
|  | MemA_8 | 1065.8399999999999 |  |  |
|  | MemA_9 | 1055.48 |  |  |
|  | MemA_10 | 1028.49 |  |  |
|  | MemA_11 | 1058.24 |  |  |
|  | MemA_12 | 1092.57 |  |  |
|  | MemA_13 | 1055.1500000000001 |  |  |
|  | MemA_14 | 1054.22 |  |  |
|  | MemRASN | 1063.3 |  |  |
|  | MemCASN | 1044.02 |  |  |
|  | MemWEN | 1055.93 |  |  |
|  | MemBA_0 | 1037.9100000000001 |  |  |
|  | MemBA_1 | 1054.42 |  |  |
|  | MemBA_2 | 1041.46 |  |  |
| CONTROL | Signal name | Length | group mismismatching<100 mil |  |
|  | DDR3 DQL |  |  |  |
|  | MemCSN | 1144.29 | OK |  |
|  | MemODT | 1131.6600000000001 |  |  |
|  | MemCKE | 1100.68 |  |  |
